(kicad_pcb
	(version 20260206)
	(generator "pcbnew")
	(generator_version "10.0")
	(general
		(thickness 1.6)
		(legacy_teardrops no)
	)
	(paper "A4")
	(title_block
		(title "03242023_DA0F0TMBIJ0_F0T_Motherboard_J_brd_V01_OCP.brd")
		(comment 1 "Grand Teton / footprints 5099-5105 of 6105")
	)
	(layers
		(0 "F.Cu" signal "TOP")
		(4 "In1.Cu" signal "GND")
		(6 "In2.Cu" signal "IN1")
		(8 "In3.Cu" signal "GND1")
		(10 "In4.Cu" signal "IN2")
		(12 "In5.Cu" signal "GND2")
		(14 "In6.Cu" signal "IN3")
		(16 "In7.Cu" signal "GND3")
		(18 "In8.Cu" signal "VCC")
		(20 "In9.Cu" signal "VCC1")
		(22 "In10.Cu" signal "GND4")
		(24 "In11.Cu" signal "IN4")
		(26 "In12.Cu" signal "GND5")
		(28 "In13.Cu" signal "IN5")
		(30 "In14.Cu" signal "GND6")
		(32 "In15.Cu" signal "IN6")
		(34 "In16.Cu" signal "GND7")
		(2 "B.Cu" signal "BOTTOM")
		(9 "F.Adhes" user "F.Adhesive")
		(11 "B.Adhes" user "B.Adhesive")
		(13 "F.Paste" user "Package Geometry/Pastemask Top")
		(15 "B.Paste" user "Package Geometry/Pastemask Bottom")
		(5 "F.SilkS" user "Ref Des/Silkscreen Top")
		(7 "B.SilkS" user "Ref Des/Silkscreen Bottom")
		(1 "F.Mask" user "Board Geometry/Soldermask Top")
		(3 "B.Mask" user "Board Geometry/Soldermask Bottom")
		(17 "Dwgs.User" user "User.Drawings")
		(19 "Cmts.User" user "User.Comments")
		(21 "Eco1.User" user "User.Eco1")
		(23 "Eco2.User" user "User.Eco2")
		(25 "Edge.Cuts" user "Board Geometry/Outline")
		(27 "Margin" user)
		(31 "F.CrtYd" user "Package Geometry/Place Bound Top")
		(29 "B.CrtYd" user "Package Geometry/Place Bound Bottom")
		(35 "F.Fab" user "Ref Des/Assembly Top")
		(33 "B.Fab" user "Ref Des/Assembly Bottom")
	)
	(footprint ""
		(layer "B.Cu")
		(at 340.036658 -354.92817 90)
		(property "Reference" "PR2554"
			(at 0 0 90)
			(layer "B.SilkS")
			(hide yes)
			(effects
				(font
					(size 1.27 1.27)
				)
				(justify mirror)
			)
		)
		(property "Value" ""
			(at 0 0 90)
			(layer "B.Fab")
			(effects
				(font
					(size 1.27 1.27)
				)
				(justify mirror)
			)
		)
		(duplicate_pad_numbers_are_jumpers no)
		(fp_line
			(start 4.0386 -1.7526)
			(end -4.0386 -1.7526)
			(stroke
				(width 0.1524)
				(type default)
			)
			(layer "B.SilkS")
		)
		(fp_line
			(start -4.0386 -1.7526)
			(end -4.0386 1.7526)
			(stroke
				(width 0.1524)
				(type default)
			)
			(layer "B.SilkS")
		)
		(fp_line
			(start 4.0386 1.7526)
			(end 4.0386 -1.7526)
			(stroke
				(width 0.1524)
				(type default)
			)
			(layer "B.SilkS")
		)
		(fp_line
			(start -4.0386 1.7526)
			(end 4.0386 1.7526)
			(stroke
				(width 0.1524)
				(type default)
			)
			(layer "B.SilkS")
		)
		(fp_line
			(start 4.0386 -1.7526)
			(end -4.0386 -1.7526)
			(stroke
				(width 0.1)
				(type default)
			)
			(layer "B.Fab")
		)
		(fp_line
			(start -4.0386 -1.7526)
			(end -4.0386 1.7526)
			(stroke
				(width 0.1)
				(type default)
			)
			(layer "B.Fab")
		)
		(fp_line
			(start 4.0386 1.7526)
			(end 4.0386 -1.7526)
			(stroke
				(width 0.1)
				(type default)
			)
			(layer "B.Fab")
		)
		(fp_line
			(start -4.0386 1.7526)
			(end 4.0386 1.7526)
			(stroke
				(width 0.1)
				(type default)
			)
			(layer "B.Fab")
		)
		(pad "1" smd rect
			(at 3.1115 0 270)
			(size 1.524 3.2004)
			(layers "B.Cu" "B.Mask" "B.Paste")
			(net "P12V_AUX")
		)
		(pad "2" smd rect
			(at -3.1115 0 270)
			(size 1.524 3.2004)
			(layers "B.Cu" "B.Mask" "B.Paste")
			(net "SW_P12V_PVCCIN_CPU0_FLT")
		)
	)
	(footprint ""
		(layer "B.Cu")
		(at 407.108152 -193.08953 -90)
		(property "Reference" "R282"
			(at 0 0 90)
			(layer "B.SilkS")
			(hide yes)
			(effects
				(font
					(size 1.27 1.27)
				)
				(justify mirror)
			)
		)
		(property "Value" ""
			(at 0 0 90)
			(layer "B.Fab")
			(effects
				(font
					(size 1.27 1.27)
				)
				(justify mirror)
			)
		)
		(duplicate_pad_numbers_are_jumpers no)
		(fp_line
			(start -0.7874 0.4064)
			(end 0.7874 0.4064)
			(stroke
				(width 0.1524)
				(type default)
			)
			(layer "B.SilkS")
		)
		(fp_line
			(start 0.7874 0.4064)
			(end 0.7874 -0.4064)
			(stroke
				(width 0.1524)
				(type default)
			)
			(layer "B.SilkS")
		)
		(fp_line
			(start -0.7874 -0.4064)
			(end -0.7874 0.4064)
			(stroke
				(width 0.1524)
				(type default)
			)
			(layer "B.SilkS")
		)
		(fp_line
			(start 0.7874 -0.4064)
			(end -0.7874 -0.4064)
			(stroke
				(width 0.1524)
				(type default)
			)
			(layer "B.SilkS")
		)
		(fp_line
			(start -0.67945 0.3048)
			(end -0.120396 0.3048)
			(stroke
				(width 0.1)
				(type default)
			)
			(layer "B.Fab")
		)
		(fp_line
			(start -0.120396 0.3048)
			(end -0.120396 0.2794)
			(stroke
				(width 0.1)
				(type default)
			)
			(layer "B.Fab")
		)
		(fp_line
			(start 0.12065 0.3048)
			(end 0.67945 0.3048)
			(stroke
				(width 0.1)
				(type default)
			)
			(layer "B.Fab")
		)
		(fp_line
			(start 0.67945 0.3048)
			(end 0.67945 -0.305054)
			(stroke
				(width 0.1)
				(type default)
			)
			(layer "B.Fab")
		)
		(fp_line
			(start -0.120396 0.2794)
			(end 0.12065 0.2794)
			(stroke
				(width 0.1)
				(type default)
			)
			(layer "B.Fab")
		)
		(fp_line
			(start 0.12065 0.2794)
			(end 0.12065 0.3048)
			(stroke
				(width 0.1)
				(type default)
			)
			(layer "B.Fab")
		)
		(fp_line
			(start -0.12065 -0.2794)
			(end -0.12065 -0.3048)
			(stroke
				(width 0.1)
				(type default)
			)
			(layer "B.Fab")
		)
		(fp_line
			(start 0.12065 -0.2794)
			(end -0.12065 -0.2794)
			(stroke
				(width 0.1)
				(type default)
			)
			(layer "B.Fab")
		)
		(fp_line
			(start -0.67945 -0.3048)
			(end -0.67945 0.3048)
			(stroke
				(width 0.1)
				(type default)
			)
			(layer "B.Fab")
		)
		(fp_line
			(start -0.12065 -0.3048)
			(end -0.67945 -0.3048)
			(stroke
				(width 0.1)
				(type default)
			)
			(layer "B.Fab")
		)
		(fp_line
			(start 0.12065 -0.305054)
			(end 0.12065 -0.2794)
			(stroke
				(width 0.1)
				(type default)
			)
			(layer "B.Fab")
		)
		(fp_line
			(start 0.67945 -0.305054)
			(end 0.12065 -0.305054)
			(stroke
				(width 0.1)
				(type default)
			)
			(layer "B.Fab")
		)
		(pad "1" smd circle
			(at 0.40005 0 90)
			(size 0 0)
			(layers "B.Cu" "B.Mask" "B.Paste")
			(net "PVNN_TERM_CPU0")
		)
		(pad "2" smd circle
			(at -0.40005 0 90)
			(size 0 0)
			(layers "B.Cu" "B.Mask" "B.Paste")
			(net "PU_CPU0_LEGACY_SKT")
		)
	)
	(footprint ""
		(layer "B.Cu")
		(at 75.87488 -11.267948 -90)
		(property "Reference" "R3165"
			(at 0 0 90)
			(layer "B.SilkS")
			(hide yes)
			(effects
				(font
					(size 1.27 1.27)
				)
				(justify mirror)
			)
		)
		(property "Value" ""
			(at 0 0 90)
			(layer "B.Fab")
			(effects
				(font
					(size 1.27 1.27)
				)
				(justify mirror)
			)
		)
		(duplicate_pad_numbers_are_jumpers no)
		(fp_line
			(start -0.7874 0.4064)
			(end 0.7874 0.4064)
			(stroke
				(width 0.1524)
				(type default)
			)
			(layer "B.SilkS")
		)
		(fp_line
			(start 0.7874 0.4064)
			(end 0.7874 -0.4064)
			(stroke
				(width 0.1524)
				(type default)
			)
			(layer "B.SilkS")
		)
		(fp_line
			(start -0.7874 -0.4064)
			(end -0.7874 0.4064)
			(stroke
				(width 0.1524)
				(type default)
			)
			(layer "B.SilkS")
		)
		(fp_line
			(start 0.7874 -0.4064)
			(end -0.7874 -0.4064)
			(stroke
				(width 0.1524)
				(type default)
			)
			(layer "B.SilkS")
		)
		(fp_line
			(start -0.67945 0.3048)
			(end -0.120396 0.3048)
			(stroke
				(width 0.1)
				(type default)
			)
			(layer "B.Fab")
		)
		(fp_line
			(start -0.120396 0.3048)
			(end -0.120396 0.2794)
			(stroke
				(width 0.1)
				(type default)
			)
			(layer "B.Fab")
		)
		(fp_line
			(start 0.12065 0.3048)
			(end 0.67945 0.3048)
			(stroke
				(width 0.1)
				(type default)
			)
			(layer "B.Fab")
		)
		(fp_line
			(start 0.67945 0.3048)
			(end 0.67945 -0.305054)
			(stroke
				(width 0.1)
				(type default)
			)
			(layer "B.Fab")
		)
		(fp_line
			(start -0.120396 0.2794)
			(end 0.12065 0.2794)
			(stroke
				(width 0.1)
				(type default)
			)
			(layer "B.Fab")
		)
		(fp_line
			(start 0.12065 0.2794)
			(end 0.12065 0.3048)
			(stroke
				(width 0.1)
				(type default)
			)
			(layer "B.Fab")
		)
		(fp_line
			(start -0.12065 -0.2794)
			(end -0.12065 -0.3048)
			(stroke
				(width 0.1)
				(type default)
			)
			(layer "B.Fab")
		)
		(fp_line
			(start 0.12065 -0.2794)
			(end -0.12065 -0.2794)
			(stroke
				(width 0.1)
				(type default)
			)
			(layer "B.Fab")
		)
		(fp_line
			(start -0.67945 -0.3048)
			(end -0.67945 0.3048)
			(stroke
				(width 0.1)
				(type default)
			)
			(layer "B.Fab")
		)
		(fp_line
			(start -0.12065 -0.3048)
			(end -0.67945 -0.3048)
			(stroke
				(width 0.1)
				(type default)
			)
			(layer "B.Fab")
		)
		(fp_line
			(start 0.12065 -0.305054)
			(end 0.12065 -0.2794)
			(stroke
				(width 0.1)
				(type default)
			)
			(layer "B.Fab")
		)
		(fp_line
			(start 0.67945 -0.305054)
			(end 0.12065 -0.305054)
			(stroke
				(width 0.1)
				(type default)
			)
			(layer "B.Fab")
		)
		(pad "1" smd circle
			(at 0.40005 0 90)
			(size 0 0)
			(layers "B.Cu" "B.Mask" "B.Paste")
			(net "GND")
		)
		(pad "2" smd circle
			(at -0.40005 0 90)
			(size 0 0)
			(layers "B.Cu" "B.Mask" "B.Paste")
			(net "OCP_V3_2_MAIN_PWR_EN")
		)
	)
	(footprint ""
		(layer "B.Cu")
		(at 414.309814 -319.263776 180)
		(property "Reference" "C26"
			(at 0 0 0)
			(layer "B.SilkS")
			(hide yes)
			(effects
				(font
					(size 1.27 1.27)
				)
				(justify mirror)
			)
		)
		(property "Value" ""
			(at 0 0 0)
			(layer "B.Fab")
			(effects
				(font
					(size 1.27 1.27)
				)
				(justify mirror)
			)
		)
		(duplicate_pad_numbers_are_jumpers no)
		(fp_line
			(start 0.7874 0.4064)
			(end 0.7874 -0.4064)
			(stroke
				(width 0.1524)
				(type default)
			)
			(layer "B.SilkS")
		)
		(fp_line
			(start 0.7874 -0.4064)
			(end -0.7874 -0.4064)
			(stroke
				(width 0.1524)
				(type default)
			)
			(layer "B.SilkS")
		)
		(fp_line
			(start -0.7874 0.4064)
			(end 0.7874 0.4064)
			(stroke
				(width 0.1524)
				(type default)
			)
			(layer "B.SilkS")
		)
		(fp_line
			(start -0.7874 -0.4064)
			(end -0.7874 0.4064)
			(stroke
				(width 0.1524)
				(type default)
			)
			(layer "B.SilkS")
		)
		(fp_line
			(start 0.67945 0.3048)
			(end 0.67945 -0.305054)
			(stroke
				(width 0.1)
				(type default)
			)
			(layer "B.Fab")
		)
		(fp_line
			(start 0.67945 -0.305054)
			(end 0.12065 -0.305054)
			(stroke
				(width 0.1)
				(type default)
			)
			(layer "B.Fab")
		)
		(fp_line
			(start 0.12065 0.3048)
			(end 0.67945 0.3048)
			(stroke
				(width 0.1)
				(type default)
			)
			(layer "B.Fab")
		)
		(fp_line
			(start 0.12065 0.2794)
			(end 0.12065 0.3048)
			(stroke
				(width 0.1)
				(type default)
			)
			(layer "B.Fab")
		)
		(fp_line
			(start 0.12065 -0.2794)
			(end -0.12065 -0.2794)
			(stroke
				(width 0.1)
				(type default)
			)
			(layer "B.Fab")
		)
		(fp_line
			(start 0.12065 -0.305054)
			(end 0.12065 -0.2794)
			(stroke
				(width 0.1)
				(type default)
			)
			(layer "B.Fab")
		)
		(fp_line
			(start -0.120396 0.3048)
			(end -0.120396 0.2794)
			(stroke
				(width 0.1)
				(type default)
			)
			(layer "B.Fab")
		)
		(fp_line
			(start -0.120396 0.2794)
			(end 0.12065 0.2794)
			(stroke
				(width 0.1)
				(type default)
			)
			(layer "B.Fab")
		)
		(fp_line
			(start -0.12065 -0.2794)
			(end -0.12065 -0.3048)
			(stroke
				(width 0.1)
				(type default)
			)
			(layer "B.Fab")
		)
		(fp_line
			(start -0.12065 -0.3048)
			(end -0.67945 -0.3048)
			(stroke
				(width 0.1)
				(type default)
			)
			(layer "B.Fab")
		)
		(fp_line
			(start -0.67945 0.3048)
			(end -0.120396 0.3048)
			(stroke
				(width 0.1)
				(type default)
			)
			(layer "B.Fab")
		)
		(fp_line
			(start -0.67945 -0.3048)
			(end -0.67945 0.3048)
			(stroke
				(width 0.1)
				(type default)
			)
			(layer "B.Fab")
		)
		(pad "1" smd circle
			(at 0.40005 0)
			(size 0 0)
			(layers "B.Cu" "B.Mask" "B.Paste")
			(net "P3V3_AUX")
		)
		(pad "2" smd circle
			(at -0.40005 0)
			(size 0 0)
			(layers "B.Cu" "B.Mask" "B.Paste")
			(net "GND")
		)
	)
	(footprint ""
		(layer "B.Cu")
		(at 447.56705 -10.594086 90)
		(property "Reference" "R410"
			(at 0 0 90)
			(layer "B.SilkS")
			(hide yes)
			(effects
				(font
					(size 1.27 1.27)
				)
				(justify mirror)
			)
		)
		(property "Value" ""
			(at 0 0 90)
			(layer "B.Fab")
			(effects
				(font
					(size 1.27 1.27)
				)
				(justify mirror)
			)
		)
		(duplicate_pad_numbers_are_jumpers no)
		(fp_line
			(start 0.7874 -0.4064)
			(end -0.7874 -0.4064)
			(stroke
				(width 0.1524)
				(type default)
			)
			(layer "B.SilkS")
		)
		(fp_line
			(start -0.7874 -0.4064)
			(end -0.7874 0.4064)
			(stroke
				(width 0.1524)
				(type default)
			)
			(layer "B.SilkS")
		)
		(fp_line
			(start 0.7874 0.4064)
			(end 0.7874 -0.4064)
			(stroke
				(width 0.1524)
				(type default)
			)
			(layer "B.SilkS")
		)
		(fp_line
			(start -0.7874 0.4064)
			(end 0.7874 0.4064)
			(stroke
				(width 0.1524)
				(type default)
			)
			(layer "B.SilkS")
		)
		(fp_line
			(start 0.67945 -0.305054)
			(end 0.12065 -0.305054)
			(stroke
				(width 0.1)
				(type default)
			)
			(layer "B.Fab")
		)
		(fp_line
			(start 0.12065 -0.305054)
			(end 0.12065 -0.2794)
			(stroke
				(width 0.1)
				(type default)
			)
			(layer "B.Fab")
		)
		(fp_line
			(start -0.12065 -0.3048)
			(end -0.67945 -0.3048)
			(stroke
				(width 0.1)
				(type default)
			)
			(layer "B.Fab")
		)
		(fp_line
			(start -0.67945 -0.3048)
			(end -0.67945 0.3048)
			(stroke
				(width 0.1)
				(type default)
			)
			(layer "B.Fab")
		)
		(fp_line
			(start 0.12065 -0.2794)
			(end -0.12065 -0.2794)
			(stroke
				(width 0.1)
				(type default)
			)
			(layer "B.Fab")
		)
		(fp_line
			(start -0.12065 -0.2794)
			(end -0.12065 -0.3048)
			(stroke
				(width 0.1)
				(type default)
			)
			(layer "B.Fab")
		)
		(fp_line
			(start 0.12065 0.2794)
			(end 0.12065 0.3048)
			(stroke
				(width 0.1)
				(type default)
			)
			(layer "B.Fab")
		)
		(fp_line
			(start -0.120396 0.2794)
			(end 0.12065 0.2794)
			(stroke
				(width 0.1)
				(type default)
			)
			(layer "B.Fab")
		)
		(fp_line
			(start 0.67945 0.3048)
			(end 0.67945 -0.305054)
			(stroke
				(width 0.1)
				(type default)
			)
			(layer "B.Fab")
		)
		(fp_line
			(start 0.12065 0.3048)
			(end 0.67945 0.3048)
			(stroke
				(width 0.1)
				(type default)
			)
			(layer "B.Fab")
		)
		(fp_line
			(start -0.120396 0.3048)
			(end -0.120396 0.2794)
			(stroke
				(width 0.1)
				(type default)
			)
			(layer "B.Fab")
		)
		(fp_line
			(start -0.67945 0.3048)
			(end -0.120396 0.3048)
			(stroke
				(width 0.1)
				(type default)
			)
			(layer "B.Fab")
		)
		(pad "1" smd circle
			(at 0.40005 0 270)
			(size 0 0)
			(layers "B.Cu" "B.Mask" "B.Paste")
			(net "OCP_SFF_ID0")
		)
		(pad "2" smd circle
			(at -0.40005 0 270)
			(size 0 0)
			(layers "B.Cu" "B.Mask" "B.Paste")
			(net "GND")
		)
	)
	(footprint ""
		(layer "B.Cu")
		(at 71.65848 -183.278018 -90)
		(property "Reference" "R264"
			(at 0 0 90)
			(layer "B.SilkS")
			(hide yes)
			(effects
				(font
					(size 1.27 1.27)
				)
				(justify mirror)
			)
		)
		(property "Value" ""
			(at 0 0 90)
			(layer "B.Fab")
			(effects
				(font
					(size 1.27 1.27)
				)
				(justify mirror)
			)
		)
		(duplicate_pad_numbers_are_jumpers no)
		(fp_line
			(start -0.7874 0.4064)
			(end 0.7874 0.4064)
			(stroke
				(width 0.1524)
				(type default)
			)
			(layer "B.SilkS")
		)
		(fp_line
			(start 0.7874 0.4064)
			(end 0.7874 -0.4064)
			(stroke
				(width 0.1524)
				(type default)
			)
			(layer "B.SilkS")
		)
		(fp_line
			(start -0.7874 -0.4064)
			(end -0.7874 0.4064)
			(stroke
				(width 0.1524)
				(type default)
			)
			(layer "B.SilkS")
		)
		(fp_line
			(start 0.7874 -0.4064)
			(end -0.7874 -0.4064)
			(stroke
				(width 0.1524)
				(type default)
			)
			(layer "B.SilkS")
		)
		(fp_line
			(start -0.67945 0.3048)
			(end -0.120396 0.3048)
			(stroke
				(width 0.1)
				(type default)
			)
			(layer "B.Fab")
		)
		(fp_line
			(start -0.120396 0.3048)
			(end -0.120396 0.2794)
			(stroke
				(width 0.1)
				(type default)
			)
			(layer "B.Fab")
		)
		(fp_line
			(start 0.12065 0.3048)
			(end 0.67945 0.3048)
			(stroke
				(width 0.1)
				(type default)
			)
			(layer "B.Fab")
		)
		(fp_line
			(start 0.67945 0.3048)
			(end 0.67945 -0.305054)
			(stroke
				(width 0.1)
				(type default)
			)
			(layer "B.Fab")
		)
		(fp_line
			(start -0.120396 0.2794)
			(end 0.12065 0.2794)
			(stroke
				(width 0.1)
				(type default)
			)
			(layer "B.Fab")
		)
		(fp_line
			(start 0.12065 0.2794)
			(end 0.12065 0.3048)
			(stroke
				(width 0.1)
				(type default)
			)
			(layer "B.Fab")
		)
		(fp_line
			(start -0.12065 -0.2794)
			(end -0.12065 -0.3048)
			(stroke
				(width 0.1)
				(type default)
			)
			(layer "B.Fab")
		)
		(fp_line
			(start 0.12065 -0.2794)
			(end -0.12065 -0.2794)
			(stroke
				(width 0.1)
				(type default)
			)
			(layer "B.Fab")
		)
		(fp_line
			(start -0.67945 -0.3048)
			(end -0.67945 0.3048)
			(stroke
				(width 0.1)
				(type default)
			)
			(layer "B.Fab")
		)
		(fp_line
			(start -0.12065 -0.3048)
			(end -0.67945 -0.3048)
			(stroke
				(width 0.1)
				(type default)
			)
			(layer "B.Fab")
		)
		(fp_line
			(start 0.12065 -0.305054)
			(end 0.12065 -0.2794)
			(stroke
				(width 0.1)
				(type default)
			)
			(layer "B.Fab")
		)
		(fp_line
			(start 0.67945 -0.305054)
			(end 0.12065 -0.305054)
			(stroke
				(width 0.1)
				(type default)
			)
			(layer "B.Fab")
		)
		(pad "1" smd circle
			(at 0.40005 0 90)
			(size 0 0)
			(layers "B.Cu" "B.Mask" "B.Paste")
			(net "PVNN_TERM_CPU1")
		)
		(pad "2" smd circle
			(at -0.40005 0 90)
			(size 0 0)
			(layers "B.Cu" "B.Mask" "B.Paste")
			(net "H_CPU1_BMCINIT_LVC1")
		)
	)
	(footprint ""
		(layer "B.Cu")
		(at 271.180814 -321.549776 -90)
		(property "Reference" "C16"
			(at 0 0 90)
			(layer "B.SilkS")
			(hide yes)
			(effects
				(font
					(size 1.27 1.27)
				)
				(justify mirror)
			)
		)
		(property "Value" ""
			(at 0 0 90)
			(layer "B.Fab")
			(effects
				(font
					(size 1.27 1.27)
				)
				(justify mirror)
			)
		)
		(duplicate_pad_numbers_are_jumpers no)
		(fp_line
			(start -1.524 0.762)
			(end 1.524 0.762)
			(stroke
				(width 0.1524)
				(type default)
			)
			(layer "B.SilkS")
		)
		(fp_line
			(start 1.524 0.762)
			(end 1.524 -0.762)
			(stroke
				(width 0.1524)
				(type default)
			)
			(layer "B.SilkS")
		)
		(fp_line
			(start -1.524 -0.762)
			(end -1.524 0.762)
			(stroke
				(width 0.1524)
				(type default)
			)
			(layer "B.SilkS")
		)
		(fp_line
			(start 1.524 -0.762)
			(end -1.524 -0.762)
			(stroke
				(width 0.1524)
				(type default)
			)
			(layer "B.SilkS")
		)
		(fp_line
			(start -1.1049 0.724916)
			(end -1.1049 -0.724916)
			(stroke
				(width 0.1)
				(type default)
			)
			(layer "B.Fab")
		)
		(fp_line
			(start 1.1049 0.724916)
			(end -1.1049 0.724916)
			(stroke
				(width 0.1)
				(type default)
			)
			(layer "B.Fab")
		)
		(fp_line
			(start -1.1049 -0.724916)
			(end 1.1049 -0.724916)
			(stroke
				(width 0.1)
				(type default)
			)
			(layer "B.Fab")
		)
		(fp_line
			(start 1.1049 -0.724916)
			(end 1.1049 0.724916)
			(stroke
				(width 0.1)
				(type default)
			)
			(layer "B.Fab")
		)
		(pad "1" smd rect
			(at 0.889 0 270)
			(size 1.016 1.27)
			(layers "B.Cu" "B.Mask" "B.Paste")
			(net "P12V_S3_AUX_CPU0_NVDIMM")
		)
		(pad "2" smd rect
			(at -0.889 0 270)
			(size 1.016 1.27)
			(layers "B.Cu" "B.Mask" "B.Paste")
			(net "GND")
		)
	)
)
